(kicad_pcb
	(version 20260206)
	(generator "pcbnew")
	(generator_version "10.0")
	(general
		(thickness 1.6)
		(legacy_teardrops no)
	)
	(paper "A4")
	(title_block
		(title "04192023_DAF0TMB3IC0_F0TG_MB_C_brd_V02_OCP.brd")
		(comment 1 "Grand Teton / footprints 2430-2436 of 8354")
	)
	(layers
		(0 "F.Cu" signal "TOP")
		(4 "In1.Cu" signal "GND")
		(6 "In2.Cu" signal "IN1")
		(8 "In3.Cu" signal "GND1")
		(10 "In4.Cu" signal "IN2")
		(12 "In5.Cu" signal "GND2")
		(14 "In6.Cu" signal "IN3")
		(16 "In7.Cu" signal "GND3")
		(18 "In8.Cu" signal "VCC")
		(20 "In9.Cu" signal "VCC1")
		(22 "In10.Cu" signal "GND4")
		(24 "In11.Cu" signal "IN4")
		(26 "In12.Cu" signal "GND5")
		(28 "In13.Cu" signal "IN5")
		(30 "In14.Cu" signal "GND6")
		(32 "In15.Cu" signal "IN6")
		(34 "In16.Cu" signal "GND7")
		(2 "B.Cu" signal "BOTTOM")
		(9 "F.Adhes" user "F.Adhesive")
		(11 "B.Adhes" user "B.Adhesive")
		(13 "F.Paste" user "Package Geometry/Pastemask Top")
		(15 "B.Paste" user "Package Geometry/Pastemask Bottom")
		(5 "F.SilkS" user "Ref Des/Silkscreen Top")
		(7 "B.SilkS" user "Ref Des/Silkscreen Bottom")
		(1 "F.Mask" user "Board Geometry/Soldermask Top")
		(3 "B.Mask" user "Board Geometry/Soldermask Bottom")
		(17 "Dwgs.User" user "User.Drawings")
		(19 "Cmts.User" user "User.Comments")
		(21 "Eco1.User" user "User.Eco1")
		(23 "Eco2.User" user "User.Eco2")
		(25 "Edge.Cuts" user "Board Geometry/Outline")
		(27 "Margin" user)
		(31 "F.CrtYd" user "Package Geometry/Place Bound Top")
		(29 "B.CrtYd" user "Package Geometry/Place Bound Bottom")
		(35 "F.Fab" user "Ref Des/Assembly Top")
		(33 "B.Fab" user "Ref Des/Assembly Bottom")
	)
	(footprint ""
		(layer "F.Cu")
		(at 73.466706 -152.990804 90)
		(property "Reference" "PC61"
			(at 0 0 90)
			(layer "F.SilkS")
			(hide yes)
			(effects
				(font
					(size 1.27 1.27)
				)
			)
		)
		(property "Value" ""
			(at 0 0 90)
			(layer "F.Fab")
			(effects
				(font
					(size 1.27 1.27)
				)
			)
		)
		(duplicate_pad_numbers_are_jumpers no)
		(fp_line
			(start 1.524 -0.762)
			(end 1.524 0.762)
			(stroke
				(width 0.1524)
				(type default)
			)
			(layer "F.SilkS")
		)
		(fp_line
			(start -1.524 -0.762)
			(end 1.524 -0.762)
			(stroke
				(width 0.1524)
				(type default)
			)
			(layer "F.SilkS")
		)
		(fp_line
			(start 1.524 0.762)
			(end -1.524 0.762)
			(stroke
				(width 0.1524)
				(type default)
			)
			(layer "F.SilkS")
		)
		(fp_line
			(start -1.524 0.762)
			(end -1.524 -0.762)
			(stroke
				(width 0.1524)
				(type default)
			)
			(layer "F.SilkS")
		)
		(fp_line
			(start 1.1049 -0.724916)
			(end -1.1049 -0.724916)
			(stroke
				(width 0.1)
				(type default)
			)
			(layer "F.Fab")
		)
		(fp_line
			(start -1.1049 -0.724916)
			(end -1.1049 0.724916)
			(stroke
				(width 0.1)
				(type default)
			)
			(layer "F.Fab")
		)
		(fp_line
			(start 1.1049 0.724916)
			(end 1.1049 -0.724916)
			(stroke
				(width 0.1)
				(type default)
			)
			(layer "F.Fab")
		)
		(fp_line
			(start -1.1049 0.724916)
			(end 1.1049 0.724916)
			(stroke
				(width 0.1)
				(type default)
			)
			(layer "F.Fab")
		)
		(pad "1" smd rect
			(at -0.889 0 270)
			(size 1.016 1.27)
			(layers "F.Cu" "F.Mask" "F.Paste")
			(net "SW_P12V_AUX_PVDD18_S5_P1_FLT")
		)
		(pad "2" smd rect
			(at 0.889 0 270)
			(size 1.016 1.27)
			(layers "F.Cu" "F.Mask" "F.Paste")
			(net "GND")
		)
	)
	(footprint ""
		(layer "F.Cu")
		(at 208.878932 -119.721376)
		(property "Reference" "R2664"
			(at 0 0 0)
			(layer "F.SilkS")
			(hide yes)
			(effects
				(font
					(size 1.27 1.27)
				)
			)
		)
		(property "Value" ""
			(at 0 0 0)
			(layer "F.Fab")
			(effects
				(font
					(size 1.27 1.27)
				)
			)
		)
		(duplicate_pad_numbers_are_jumpers no)
		(fp_line
			(start -0.7874 -0.4064)
			(end 0.7874 -0.4064)
			(stroke
				(width 0.1524)
				(type default)
			)
			(layer "F.SilkS")
		)
		(fp_line
			(start -0.7874 0.4064)
			(end -0.7874 -0.4064)
			(stroke
				(width 0.1524)
				(type default)
			)
			(layer "F.SilkS")
		)
		(fp_line
			(start 0.7874 -0.4064)
			(end 0.7874 0.4064)
			(stroke
				(width 0.1524)
				(type default)
			)
			(layer "F.SilkS")
		)
		(fp_line
			(start 0.7874 0.4064)
			(end -0.7874 0.4064)
			(stroke
				(width 0.1524)
				(type default)
			)
			(layer "F.SilkS")
		)
		(fp_line
			(start -0.67945 -0.305054)
			(end -0.12065 -0.305054)
			(stroke
				(width 0.1)
				(type default)
			)
			(layer "F.Fab")
		)
		(fp_line
			(start -0.67945 0.3048)
			(end -0.67945 -0.305054)
			(stroke
				(width 0.1)
				(type default)
			)
			(layer "F.Fab")
		)
		(fp_line
			(start -0.12065 -0.305054)
			(end -0.12065 -0.2794)
			(stroke
				(width 0.1)
				(type default)
			)
			(layer "F.Fab")
		)
		(fp_line
			(start -0.12065 -0.2794)
			(end 0.12065 -0.2794)
			(stroke
				(width 0.1)
				(type default)
			)
			(layer "F.Fab")
		)
		(fp_line
			(start -0.12065 0.2794)
			(end -0.12065 0.3048)
			(stroke
				(width 0.1)
				(type default)
			)
			(layer "F.Fab")
		)
		(fp_line
			(start -0.12065 0.3048)
			(end -0.67945 0.3048)
			(stroke
				(width 0.1)
				(type default)
			)
			(layer "F.Fab")
		)
		(fp_line
			(start 0.120396 0.2794)
			(end -0.12065 0.2794)
			(stroke
				(width 0.1)
				(type default)
			)
			(layer "F.Fab")
		)
		(fp_line
			(start 0.120396 0.3048)
			(end 0.120396 0.2794)
			(stroke
				(width 0.1)
				(type default)
			)
			(layer "F.Fab")
		)
		(fp_line
			(start 0.12065 -0.3048)
			(end 0.67945 -0.3048)
			(stroke
				(width 0.1)
				(type default)
			)
			(layer "F.Fab")
		)
		(fp_line
			(start 0.12065 -0.2794)
			(end 0.12065 -0.3048)
			(stroke
				(width 0.1)
				(type default)
			)
			(layer "F.Fab")
		)
		(fp_line
			(start 0.67945 -0.3048)
			(end 0.67945 0.3048)
			(stroke
				(width 0.1)
				(type default)
			)
			(layer "F.Fab")
		)
		(fp_line
			(start 0.67945 0.3048)
			(end 0.120396 0.3048)
			(stroke
				(width 0.1)
				(type default)
			)
			(layer "F.Fab")
		)
		(pad "1" smd circle
			(at -0.40005 0)
			(size 0 0)
			(layers "F.Cu" "F.Mask" "F.Paste")
			(net "FM_GPU_PWRGD_ISO_R")
		)
		(pad "2" smd circle
			(at 0.40005 0)
			(size 0 0)
			(layers "F.Cu" "F.Mask" "F.Paste")
			(net "FM_GPU_PWRGD_ISO")
		)
	)
	(footprint ""
		(layer "F.Cu")
		(at 279.513792 -115.66017 180)
		(property "Reference" "R2967"
			(at 0 0 180)
			(layer "F.SilkS")
			(hide yes)
			(effects
				(font
					(size 1.27 1.27)
				)
			)
		)
		(property "Value" ""
			(at 0 0 180)
			(layer "F.Fab")
			(effects
				(font
					(size 1.27 1.27)
				)
			)
		)
		(duplicate_pad_numbers_are_jumpers no)
		(fp_line
			(start 0.7874 0.4064)
			(end -0.7874 0.4064)
			(stroke
				(width 0.1524)
				(type default)
			)
			(layer "F.SilkS")
		)
		(fp_line
			(start 0.7874 -0.4064)
			(end 0.7874 0.4064)
			(stroke
				(width 0.1524)
				(type default)
			)
			(layer "F.SilkS")
		)
		(fp_line
			(start -0.7874 0.4064)
			(end -0.7874 -0.4064)
			(stroke
				(width 0.1524)
				(type default)
			)
			(layer "F.SilkS")
		)
		(fp_line
			(start -0.7874 -0.4064)
			(end 0.7874 -0.4064)
			(stroke
				(width 0.1524)
				(type default)
			)
			(layer "F.SilkS")
		)
		(fp_line
			(start 0.67945 0.3048)
			(end 0.120396 0.3048)
			(stroke
				(width 0.1)
				(type default)
			)
			(layer "F.Fab")
		)
		(fp_line
			(start 0.67945 -0.3048)
			(end 0.67945 0.3048)
			(stroke
				(width 0.1)
				(type default)
			)
			(layer "F.Fab")
		)
		(fp_line
			(start 0.12065 -0.2794)
			(end 0.12065 -0.3048)
			(stroke
				(width 0.1)
				(type default)
			)
			(layer "F.Fab")
		)
		(fp_line
			(start 0.12065 -0.3048)
			(end 0.67945 -0.3048)
			(stroke
				(width 0.1)
				(type default)
			)
			(layer "F.Fab")
		)
		(fp_line
			(start 0.120396 0.3048)
			(end 0.120396 0.2794)
			(stroke
				(width 0.1)
				(type default)
			)
			(layer "F.Fab")
		)
		(fp_line
			(start 0.120396 0.2794)
			(end -0.12065 0.2794)
			(stroke
				(width 0.1)
				(type default)
			)
			(layer "F.Fab")
		)
		(fp_line
			(start -0.12065 0.3048)
			(end -0.67945 0.3048)
			(stroke
				(width 0.1)
				(type default)
			)
			(layer "F.Fab")
		)
		(fp_line
			(start -0.12065 0.2794)
			(end -0.12065 0.3048)
			(stroke
				(width 0.1)
				(type default)
			)
			(layer "F.Fab")
		)
		(fp_line
			(start -0.12065 -0.2794)
			(end 0.12065 -0.2794)
			(stroke
				(width 0.1)
				(type default)
			)
			(layer "F.Fab")
		)
		(fp_line
			(start -0.12065 -0.305054)
			(end -0.12065 -0.2794)
			(stroke
				(width 0.1)
				(type default)
			)
			(layer "F.Fab")
		)
		(fp_line
			(start -0.67945 0.3048)
			(end -0.67945 -0.305054)
			(stroke
				(width 0.1)
				(type default)
			)
			(layer "F.Fab")
		)
		(fp_line
			(start -0.67945 -0.305054)
			(end -0.12065 -0.305054)
			(stroke
				(width 0.1)
				(type default)
			)
			(layer "F.Fab")
		)
		(pad "1" smd circle
			(at -0.40005 0 180)
			(size 0 0)
			(layers "F.Cu" "F.Mask" "F.Paste")
			(net "SMB_PCIE0_3V3AUX_SCL_R3")
		)
		(pad "2" smd circle
			(at 0.40005 0 180)
			(size 0 0)
			(layers "F.Cu" "F.Mask" "F.Paste")
			(net "SMB_SENSOR_M2_P1_3V3AUX_SCL")
		)
	)
	(footprint ""
		(layer "F.Cu")
		(at 142.729712 -73.623932)
		(property "Reference" "PR6007"
			(at 0 0 0)
			(layer "F.SilkS")
			(hide yes)
			(effects
				(font
					(size 1.27 1.27)
				)
			)
		)
		(property "Value" ""
			(at 0 0 0)
			(layer "F.Fab")
			(effects
				(font
					(size 1.27 1.27)
				)
			)
		)
		(duplicate_pad_numbers_are_jumpers no)
		(fp_line
			(start -0.7874 -0.4064)
			(end 0.7874 -0.4064)
			(stroke
				(width 0.1524)
				(type default)
			)
			(layer "F.SilkS")
		)
		(fp_line
			(start -0.7874 0.4064)
			(end -0.7874 -0.4064)
			(stroke
				(width 0.1524)
				(type default)
			)
			(layer "F.SilkS")
		)
		(fp_line
			(start 0.7874 -0.4064)
			(end 0.7874 0.4064)
			(stroke
				(width 0.1524)
				(type default)
			)
			(layer "F.SilkS")
		)
		(fp_line
			(start 0.7874 0.4064)
			(end -0.7874 0.4064)
			(stroke
				(width 0.1524)
				(type default)
			)
			(layer "F.SilkS")
		)
		(fp_line
			(start -0.67945 -0.305054)
			(end -0.12065 -0.305054)
			(stroke
				(width 0.1)
				(type default)
			)
			(layer "F.Fab")
		)
		(fp_line
			(start -0.67945 0.3048)
			(end -0.67945 -0.305054)
			(stroke
				(width 0.1)
				(type default)
			)
			(layer "F.Fab")
		)
		(fp_line
			(start -0.12065 -0.305054)
			(end -0.12065 -0.2794)
			(stroke
				(width 0.1)
				(type default)
			)
			(layer "F.Fab")
		)
		(fp_line
			(start -0.12065 -0.2794)
			(end 0.12065 -0.2794)
			(stroke
				(width 0.1)
				(type default)
			)
			(layer "F.Fab")
		)
		(fp_line
			(start -0.12065 0.2794)
			(end -0.12065 0.3048)
			(stroke
				(width 0.1)
				(type default)
			)
			(layer "F.Fab")
		)
		(fp_line
			(start -0.12065 0.3048)
			(end -0.67945 0.3048)
			(stroke
				(width 0.1)
				(type default)
			)
			(layer "F.Fab")
		)
		(fp_line
			(start 0.120396 0.2794)
			(end -0.12065 0.2794)
			(stroke
				(width 0.1)
				(type default)
			)
			(layer "F.Fab")
		)
		(fp_line
			(start 0.120396 0.3048)
			(end 0.120396 0.2794)
			(stroke
				(width 0.1)
				(type default)
			)
			(layer "F.Fab")
		)
		(fp_line
			(start 0.12065 -0.3048)
			(end 0.67945 -0.3048)
			(stroke
				(width 0.1)
				(type default)
			)
			(layer "F.Fab")
		)
		(fp_line
			(start 0.12065 -0.2794)
			(end 0.12065 -0.3048)
			(stroke
				(width 0.1)
				(type default)
			)
			(layer "F.Fab")
		)
		(fp_line
			(start 0.67945 -0.3048)
			(end 0.67945 0.3048)
			(stroke
				(width 0.1)
				(type default)
			)
			(layer "F.Fab")
		)
		(fp_line
			(start 0.67945 0.3048)
			(end 0.120396 0.3048)
			(stroke
				(width 0.1)
				(type default)
			)
			(layer "F.Fab")
		)
		(pad "1" smd circle
			(at -0.40005 0)
			(size 0 0)
			(layers "F.Cu" "F.Mask" "F.Paste")
			(net "P1V8_AUX_FB")
		)
		(pad "2" smd circle
			(at 0.40005 0)
			(size 0 0)
			(layers "F.Cu" "F.Mask" "F.Paste")
			(net "P1V8_AUX")
		)
	)
	(footprint ""
		(layer "F.Cu")
		(at 430.664366 -392.879072 -90)
		(property "Reference" "C667"
			(at 0 0 270)
			(layer "F.SilkS")
			(hide yes)
			(effects
				(font
					(size 1.27 1.27)
				)
			)
		)
		(property "Value" ""
			(at 0 0 270)
			(layer "F.Fab")
			(effects
				(font
					(size 1.27 1.27)
				)
			)
		)
		(duplicate_pad_numbers_are_jumpers no)
		(fp_line
			(start -0.7874 0.4064)
			(end -0.7874 -0.4064)
			(stroke
				(width 0.1524)
				(type default)
			)
			(layer "F.SilkS")
		)
		(fp_line
			(start 0.7874 0.4064)
			(end -0.7874 0.4064)
			(stroke
				(width 0.1524)
				(type default)
			)
			(layer "F.SilkS")
		)
		(fp_line
			(start -0.7874 -0.4064)
			(end 0.7874 -0.4064)
			(stroke
				(width 0.1524)
				(type default)
			)
			(layer "F.SilkS")
		)
		(fp_line
			(start 0.7874 -0.4064)
			(end 0.7874 0.4064)
			(stroke
				(width 0.1524)
				(type default)
			)
			(layer "F.SilkS")
		)
		(fp_line
			(start -0.67945 0.3048)
			(end -0.67945 -0.305054)
			(stroke
				(width 0.1)
				(type default)
			)
			(layer "F.Fab")
		)
		(fp_line
			(start -0.12065 0.3048)
			(end -0.67945 0.3048)
			(stroke
				(width 0.1)
				(type default)
			)
			(layer "F.Fab")
		)
		(fp_line
			(start 0.120396 0.3048)
			(end 0.120396 0.2794)
			(stroke
				(width 0.1)
				(type default)
			)
			(layer "F.Fab")
		)
		(fp_line
			(start 0.67945 0.3048)
			(end 0.120396 0.3048)
			(stroke
				(width 0.1)
				(type default)
			)
			(layer "F.Fab")
		)
		(fp_line
			(start -0.12065 0.2794)
			(end -0.12065 0.3048)
			(stroke
				(width 0.1)
				(type default)
			)
			(layer "F.Fab")
		)
		(fp_line
			(start 0.120396 0.2794)
			(end -0.12065 0.2794)
			(stroke
				(width 0.1)
				(type default)
			)
			(layer "F.Fab")
		)
		(fp_line
			(start -0.12065 -0.2794)
			(end 0.12065 -0.2794)
			(stroke
				(width 0.1)
				(type default)
			)
			(layer "F.Fab")
		)
		(fp_line
			(start 0.12065 -0.2794)
			(end 0.12065 -0.3048)
			(stroke
				(width 0.1)
				(type default)
			)
			(layer "F.Fab")
		)
		(fp_line
			(start 0.12065 -0.3048)
			(end 0.67945 -0.3048)
			(stroke
				(width 0.1)
				(type default)
			)
			(layer "F.Fab")
		)
		(fp_line
			(start 0.67945 -0.3048)
			(end 0.67945 0.3048)
			(stroke
				(width 0.1)
				(type default)
			)
			(layer "F.Fab")
		)
		(fp_line
			(start -0.67945 -0.305054)
			(end -0.12065 -0.305054)
			(stroke
				(width 0.1)
				(type default)
			)
			(layer "F.Fab")
		)
		(fp_line
			(start -0.12065 -0.305054)
			(end -0.12065 -0.2794)
			(stroke
				(width 0.1)
				(type default)
			)
			(layer "F.Fab")
		)
		(pad "1" smd circle
			(at -0.40005 0 270)
			(size 0 0)
			(layers "F.Cu" "F.Mask" "F.Paste")
			(net "P1V8_CPU0_RT_1D")
		)
		(pad "2" smd circle
			(at 0.40005 0 270)
			(size 0 0)
			(layers "F.Cu" "F.Mask" "F.Paste")
			(net "GND")
		)
	)
	(footprint ""
		(layer "F.Cu")
		(at 103.847138 -330.622148)
		(property "Reference" "PL69"
			(at -3.115056 -15.887446 0)
			(unlocked yes)
			(layer "F.SilkS")
			(effects
				(font
					(size 0.7874 0.5842)
					(thickness 0.1524)
				)
				(justify left)
			)
		)
		(property "Value" ""
			(at 0 0 0)
			(layer "F.Fab")
			(effects
				(font
					(size 1.27 1.27)
				)
			)
		)
		(duplicate_pad_numbers_are_jumpers no)
		(fp_line
			(start -3.750056 -5.500116)
			(end -2.393442 -5.500116)
			(stroke
				(width 0.1524)
				(type default)
			)
			(layer "F.SilkS")
		)
		(fp_line
			(start -3.750056 5.500116)
			(end -3.750056 -5.500116)
			(stroke
				(width 0.1524)
				(type default)
			)
			(layer "F.SilkS")
		)
		(fp_line
			(start -2.393442 5.500116)
			(end -3.750056 5.500116)
			(stroke
				(width 0.1524)
				(type default)
			)
			(layer "F.SilkS")
		)
		(fp_line
			(start 2.393442 5.500116)
			(end 3.750056 5.500116)
			(stroke
				(width 0.1524)
				(type default)
			)
			(layer "F.SilkS")
		)
		(fp_line
			(start 3.750056 -5.500116)
			(end 2.393442 -5.500116)
			(stroke
				(width 0.1524)
				(type default)
			)
			(layer "F.SilkS")
		)
		(fp_line
			(start 3.750056 5.500116)
			(end 3.750056 -5.500116)
			(stroke
				(width 0.1524)
				(type default)
			)
			(layer "F.SilkS")
		)
		(fp_poly
			(pts
				(xy -3.847084 -5.385308) (xy -4.305046 -5.537962) (xy -3.999738 -5.84327)
			)
			(stroke
				(width 0)
				(type default)
			)
			(fill yes)
			(layer "F.SilkS")
		)
		(fp_line
			(start -3.750056 -5.500116)
			(end -3.750056 5.500116)
			(stroke
				(width 0.1)
				(type default)
			)
			(layer "F.Fab")
		)
		(fp_line
			(start -3.750056 5.500116)
			(end 3.750056 5.500116)
			(stroke
				(width 0.1)
				(type default)
			)
			(layer "F.Fab")
		)
		(fp_line
			(start 3.750056 -5.500116)
			(end -3.750056 -5.500116)
			(stroke
				(width 0.1)
				(type default)
			)
			(layer "F.Fab")
		)
		(fp_line
			(start 3.750056 5.500116)
			(end 3.750056 -5.500116)
			(stroke
				(width 0.1)
				(type default)
			)
			(layer "F.Fab")
		)
		(fp_poly
			(pts
				(xy -4.9276 -4.757928) (xy -4.9276 -3.741928) (xy -3.9116 -4.249928)
			)
			(stroke
				(width 0)
				(type default)
			)
			(fill yes)
			(layer "F.Fab")
		)
		(pad "1" smd rect
			(at 0 -4.249928 270)
			(size 2.413 4.5212)
			(layers "F.Cu" "F.Mask" "F.Paste")
			(net "SW_PVDDCR_CPU1_P1_SW6")
		)
		(pad "2" smd rect
			(at 0 -1.175004 270)
			(size 1.3716 4.5212)
			(layers "F.Cu" "F.Mask" "F.Paste")
			(net "IND_CPU1_P1_CPL0")
		)
		(pad "3" smd rect
			(at 0 1.175004 270)
			(size 1.3716 4.5212)
			(layers "F.Cu" "F.Mask" "F.Paste")
			(net "IND_CPU1_P1_CPL6")
		)
		(pad "4" smd rect
			(at 0 4.249928 270)
			(size 2.413 4.5212)
			(layers "F.Cu" "F.Mask" "F.Paste")
			(net "PVDDCR_CPU1_P1")
		)
	)
	(footprint ""
		(layer "F.Cu")
		(at 297.741594 -392.1252)
		(property "Reference" "R985"
			(at 0 0 0)
			(layer "F.SilkS")
			(hide yes)
			(effects
				(font
					(size 1.27 1.27)
				)
			)
		)
		(property "Value" ""
			(at 0 0 0)
			(layer "F.Fab")
			(effects
				(font
					(size 1.27 1.27)
				)
			)
		)
		(duplicate_pad_numbers_are_jumpers no)
		(fp_line
			(start -0.32512 -0.175006)
			(end 0.32512 -0.175006)
			(stroke
				(width 0.1)
				(type default)
			)
			(layer "F.Fab")
		)
		(fp_line
			(start -0.32512 0.175006)
			(end -0.32512 -0.175006)
			(stroke
				(width 0.1)
				(type default)
			)
			(layer "F.Fab")
		)
		(fp_line
			(start 0.32512 -0.175006)
			(end 0.32512 0.175006)
			(stroke
				(width 0.1)
				(type default)
			)
			(layer "F.Fab")
		)
		(fp_line
			(start 0.32512 0.175006)
			(end -0.32512 0.175006)
			(stroke
				(width 0.1)
				(type default)
			)
			(layer "F.Fab")
		)
		(pad "1" smd rect
			(at -0.2667 0)
			(size 0.3048 0.381)
			(layers "F.Cu" "F.Mask" "F.Paste")
			(net "P1V8_CPU0_RT_1D")
		)
		(pad "2" smd rect
			(at 0.2667 0 180)
			(size 0.3048 0.381)
			(layers "F.Cu" "F.Mask" "F.Paste")
			(net "TEST2_RT_CPU0_P0")
		)
	)
)
